(kicad_pcb
	(version 20260206)
	(generator "pcbnew")
	(generator_version "10.0")
	(general
		(thickness 1.6)
		(legacy_teardrops no)
	)
	(paper "A4")
	(title_block
		(title "03242023_DA0F0TMBIJ0_F0T_Motherboard_J_brd_V01_OCP.brd")
		(comment 1 "Grand Teton / footprints 1373-1377 of 6105")
	)
	(layers
		(0 "F.Cu" signal "TOP")
		(4 "In1.Cu" signal "GND")
		(6 "In2.Cu" signal "IN1")
		(8 "In3.Cu" signal "GND1")
		(10 "In4.Cu" signal "IN2")
		(12 "In5.Cu" signal "GND2")
		(14 "In6.Cu" signal "IN3")
		(16 "In7.Cu" signal "GND3")
		(18 "In8.Cu" signal "VCC")
		(20 "In9.Cu" signal "VCC1")
		(22 "In10.Cu" signal "GND4")
		(24 "In11.Cu" signal "IN4")
		(26 "In12.Cu" signal "GND5")
		(28 "In13.Cu" signal "IN5")
		(30 "In14.Cu" signal "GND6")
		(32 "In15.Cu" signal "IN6")
		(34 "In16.Cu" signal "GND7")
		(2 "B.Cu" signal "BOTTOM")
		(9 "F.Adhes" user "F.Adhesive")
		(11 "B.Adhes" user "B.Adhesive")
		(13 "F.Paste" user "Package Geometry/Pastemask Top")
		(15 "B.Paste" user "Package Geometry/Pastemask Bottom")
		(5 "F.SilkS" user "Ref Des/Silkscreen Top")
		(7 "B.SilkS" user "Ref Des/Silkscreen Bottom")
		(1 "F.Mask" user "Board Geometry/Soldermask Top")
		(3 "B.Mask" user "Board Geometry/Soldermask Bottom")
		(17 "Dwgs.User" user "User.Drawings")
		(19 "Cmts.User" user "User.Comments")
		(21 "Eco1.User" user "User.Eco1")
		(23 "Eco2.User" user "User.Eco2")
		(25 "Edge.Cuts" user "Board Geometry/Outline")
		(27 "Margin" user)
		(31 "F.CrtYd" user "Package Geometry/Place Bound Top")
		(29 "B.CrtYd" user "Package Geometry/Place Bound Bottom")
		(35 "F.Fab" user "Ref Des/Assembly Top")
		(33 "B.Fab" user "Ref Des/Assembly Bottom")
	)
	(footprint ""
		(layer "F.Cu")
		(at 17.314926 -417.202366 90)
		(property "Reference" "U181"
			(at 1.322324 -8.237728 0)
			(unlocked yes)
			(layer "F.SilkS")
			(effects
				(font
					(size 0.7874 0.5842)
					(thickness 0.1524)
				)
				(justify left)
			)
		)
		(property "Value" ""
			(at 0 0 90)
			(layer "F.Fab")
			(effects
				(font
					(size 1.27 1.27)
				)
			)
		)
		(duplicate_pad_numbers_are_jumpers no)
		(fp_line
			(start 2.097532 -3.949954)
			(end 1.409954 -3.949954)
			(stroke
				(width 0.1524)
				(type default)
			)
			(layer "F.SilkS")
		)
		(fp_line
			(start 1.409954 -3.949954)
			(end 0 -2.54)
			(stroke
				(width 0.1524)
				(type default)
			)
			(layer "F.SilkS")
		)
		(fp_line
			(start -1.409954 -3.949954)
			(end -2.097532 -3.949954)
			(stroke
				(width 0.1524)
				(type default)
			)
			(layer "F.SilkS")
		)
		(fp_line
			(start -2.097532 -3.949954)
			(end -2.097532 3.949954)
			(stroke
				(width 0.1524)
				(type default)
			)
			(layer "F.SilkS")
		)
		(fp_line
			(start 0 -2.54)
			(end -1.409954 -3.949954)
			(stroke
				(width 0.1524)
				(type default)
			)
			(layer "F.SilkS")
		)
		(fp_line
			(start 2.097532 3.949954)
			(end 2.097532 -3.949954)
			(stroke
				(width 0.1524)
				(type default)
			)
			(layer "F.SilkS")
		)
		(fp_line
			(start -2.097532 3.949954)
			(end 2.097532 3.949954)
			(stroke
				(width 0.1524)
				(type default)
			)
			(layer "F.SilkS")
		)
		(fp_poly
			(pts
				(xy -2.496312 -5.281168) (xy -3.004312 -4.265168) (xy -3.512312 -5.281168)
			)
			(stroke
				(width 0)
				(type default)
			)
			(fill yes)
			(layer "F.SilkS")
		)
		(fp_line
			(start 2.249932 -3.949954)
			(end -2.249932 -3.949954)
			(stroke
				(width 0.1)
				(type default)
			)
			(layer "F.Fab")
		)
		(fp_line
			(start -2.249932 -3.949954)
			(end -2.249932 3.949954)
			(stroke
				(width 0.1)
				(type default)
			)
			(layer "F.Fab")
		)
		(fp_line
			(start 2.249932 3.949954)
			(end 2.249932 -3.949954)
			(stroke
				(width 0.1)
				(type default)
			)
			(layer "F.Fab")
		)
		(fp_line
			(start -2.249932 3.949954)
			(end 2.249932 3.949954)
			(stroke
				(width 0.1)
				(type default)
			)
			(layer "F.Fab")
		)
		(fp_poly
			(pts
				(xy -4.7498 -4.182872) (xy -4.7498 -3.166872) (xy -3.7338 -3.674872)
			)
			(stroke
				(width 0)
				(type default)
			)
			(fill yes)
			(layer "F.Fab")
		)
		(pad "1" smd rect
			(at -2.925064 -3.674872)
			(size 0.6096 1.3716)
			(layers "F.Cu" "F.Mask" "F.Paste")
			(net "PU_U181_INT")
		)
		(pad "2" smd rect
			(at -2.925064 -2.925064)
			(size 0.4064 1.3716)
			(layers "F.Cu" "F.Mask" "F.Paste")
			(net "TCA9539_0_ADD1")
		)
		(pad "3" smd rect
			(at -2.925064 -2.275078)
			(size 0.4064 1.3716)
			(layers "F.Cu" "F.Mask" "F.Paste")
			(net "PU_RST_SMB_U181_N")
		)
		(pad "4" smd rect
			(at -2.925064 -1.625092)
			(size 0.4064 1.3716)
			(layers "F.Cu" "F.Mask" "F.Paste")
			(net "RST_USB_HUB_N")
		)
		(pad "5" smd rect
			(at -2.925064 -0.975106)
			(size 0.4064 1.3716)
			(layers "F.Cu" "F.Mask" "F.Paste")
			(net "RST_SWB_BIC_N")
		)
		(pad "6" smd rect
			(at -2.925064 -0.32512)
			(size 0.4064 1.3716)
			(layers "F.Cu" "F.Mask" "F.Paste")
			(net "TP_TCA9539_0_P0_2")
		)
		(pad "7" smd rect
			(at -2.925064 0.32512)
			(size 0.4064 1.3716)
			(layers "F.Cu" "F.Mask" "F.Paste")
			(net "TP_TCA9539_0_P0_3")
		)
		(pad "8" smd rect
			(at -2.925064 0.975106)
			(size 0.4064 1.3716)
			(layers "F.Cu" "F.Mask" "F.Paste")
			(net "PRSNT_SWB_ISO_R1_N")
		)
		(pad "9" smd rect
			(at -2.925064 1.625092)
			(size 0.4064 1.3716)
			(layers "F.Cu" "F.Mask" "F.Paste")
			(net "GPU_PRSNT_N_ISO_R1")
		)
		(pad "10" smd rect
			(at -2.925064 2.275078)
			(size 0.4064 1.3716)
			(layers "F.Cu" "F.Mask" "F.Paste")
			(net "PRSNT_CABLE_GPU_B3_ISO_R1_N")
		)
		(pad "11" smd rect
			(at -2.925064 2.925064)
			(size 0.4064 1.3716)
			(layers "F.Cu" "F.Mask" "F.Paste")
			(net "PRSNT_CABLE_SWB_B2_ISO_R_N")
		)
		(pad "12" smd rect
			(at -2.925064 3.674872)
			(size 0.6096 1.3716)
			(layers "F.Cu" "F.Mask" "F.Paste")
			(net "GND")
		)
		(pad "13" smd rect
			(at 2.925064 3.674872)
			(size 0.6096 1.3716)
			(layers "F.Cu" "F.Mask" "F.Paste")
			(net "PRSNT_CABLE_GPU_A2_ISO_R1_N")
		)
		(pad "14" smd rect
			(at 2.925064 2.925064)
			(size 0.4064 1.3716)
			(layers "F.Cu" "F.Mask" "F.Paste")
			(net "PRSNT_CABLE_SWB_B1_ISO_R_N")
		)
		(pad "15" smd rect
			(at 2.925064 2.275078)
			(size 0.4064 1.3716)
			(layers "F.Cu" "F.Mask" "F.Paste")
			(net "GPU_BASE_ID0_R")
		)
		(pad "16" smd rect
			(at 2.925064 1.625092)
			(size 0.4064 1.3716)
			(layers "F.Cu" "F.Mask" "F.Paste")
			(net "GPU_BASE_ID1_R")
		)
		(pad "17" smd rect
			(at 2.925064 0.975106)
			(size 0.4064 1.3716)
			(layers "F.Cu" "F.Mask" "F.Paste")
			(net "GPU_PEX_STRAP0_R")
		)
		(pad "18" smd rect
			(at 2.925064 0.32512)
			(size 0.4064 1.3716)
			(layers "F.Cu" "F.Mask" "F.Paste")
			(net "GPU_PEX_STRAP1_R")
		)
		(pad "19" smd rect
			(at 2.925064 -0.32512)
			(size 0.4064 1.3716)
			(layers "F.Cu" "F.Mask" "F.Paste")
			(net "PRSNT_CABLE_GPU_A1_ISO_R1_N")
		)
		(pad "20" smd rect
			(at 2.925064 -0.975106)
			(size 0.4064 1.3716)
			(layers "F.Cu" "F.Mask" "F.Paste")
			(net "PRSNT_CABLE_GPU_A3_ISO_R_N")
		)
		(pad "21" smd rect
			(at 2.925064 -1.625092)
			(size 0.4064 1.3716)
			(layers "F.Cu" "F.Mask" "F.Paste")
			(net "TCA9539_0_ADD0")
		)
		(pad "22" smd rect
			(at 2.925064 -2.275078)
			(size 0.4064 1.3716)
			(layers "F.Cu" "F.Mask" "F.Paste")
			(net "SMB_IOEXP_3V3AUX_SCL_R1")
		)
		(pad "23" smd rect
			(at 2.925064 -2.925064)
			(size 0.4064 1.3716)
			(layers "F.Cu" "F.Mask" "F.Paste")
			(net "SMB_IOEXP_3V3AUX_SDA_R1")
		)
		(pad "24" smd rect
			(at 2.925064 -3.674872)
			(size 0.6096 1.3716)
			(layers "F.Cu" "F.Mask" "F.Paste")
			(net "P3V3_AUX")
		)
	)
	(footprint ""
		(layer "F.Cu")
		(at 21.176996 -97.083626 180)
		(property "Reference" "R3663"
			(at 0 0 180)
			(layer "F.SilkS")
			(hide yes)
			(effects
				(font
					(size 1.27 1.27)
				)
			)
		)
		(property "Value" ""
			(at 0 0 180)
			(layer "F.Fab")
			(effects
				(font
					(size 1.27 1.27)
				)
			)
		)
		(duplicate_pad_numbers_are_jumpers no)
		(fp_line
			(start 0.7874 0.4064)
			(end -0.7874 0.4064)
			(stroke
				(width 0.1524)
				(type default)
			)
			(layer "F.SilkS")
		)
		(fp_line
			(start 0.7874 -0.4064)
			(end 0.7874 0.4064)
			(stroke
				(width 0.1524)
				(type default)
			)
			(layer "F.SilkS")
		)
		(fp_line
			(start -0.7874 0.4064)
			(end -0.7874 -0.4064)
			(stroke
				(width 0.1524)
				(type default)
			)
			(layer "F.SilkS")
		)
		(fp_line
			(start -0.7874 -0.4064)
			(end 0.7874 -0.4064)
			(stroke
				(width 0.1524)
				(type default)
			)
			(layer "F.SilkS")
		)
		(fp_line
			(start 0.67945 0.3048)
			(end 0.120396 0.3048)
			(stroke
				(width 0.1)
				(type default)
			)
			(layer "F.Fab")
		)
		(fp_line
			(start 0.67945 -0.3048)
			(end 0.67945 0.3048)
			(stroke
				(width 0.1)
				(type default)
			)
			(layer "F.Fab")
		)
		(fp_line
			(start 0.12065 -0.2794)
			(end 0.12065 -0.3048)
			(stroke
				(width 0.1)
				(type default)
			)
			(layer "F.Fab")
		)
		(fp_line
			(start 0.12065 -0.3048)
			(end 0.67945 -0.3048)
			(stroke
				(width 0.1)
				(type default)
			)
			(layer "F.Fab")
		)
		(fp_line
			(start 0.120396 0.3048)
			(end 0.120396 0.2794)
			(stroke
				(width 0.1)
				(type default)
			)
			(layer "F.Fab")
		)
		(fp_line
			(start 0.120396 0.2794)
			(end -0.12065 0.2794)
			(stroke
				(width 0.1)
				(type default)
			)
			(layer "F.Fab")
		)
		(fp_line
			(start -0.12065 0.3048)
			(end -0.67945 0.3048)
			(stroke
				(width 0.1)
				(type default)
			)
			(layer "F.Fab")
		)
		(fp_line
			(start -0.12065 0.2794)
			(end -0.12065 0.3048)
			(stroke
				(width 0.1)
				(type default)
			)
			(layer "F.Fab")
		)
		(fp_line
			(start -0.12065 -0.2794)
			(end 0.12065 -0.2794)
			(stroke
				(width 0.1)
				(type default)
			)
			(layer "F.Fab")
		)
		(fp_line
			(start -0.12065 -0.305054)
			(end -0.12065 -0.2794)
			(stroke
				(width 0.1)
				(type default)
			)
			(layer "F.Fab")
		)
		(fp_line
			(start -0.67945 0.3048)
			(end -0.67945 -0.305054)
			(stroke
				(width 0.1)
				(type default)
			)
			(layer "F.Fab")
		)
		(fp_line
			(start -0.67945 -0.305054)
			(end -0.12065 -0.305054)
			(stroke
				(width 0.1)
				(type default)
			)
			(layer "F.Fab")
		)
		(pad "1" smd circle
			(at -0.40005 0 180)
			(size 0 0)
			(layers "F.Cu" "F.Mask" "F.Paste")
			(net "P3V3_AUX")
		)
		(pad "2" smd circle
			(at 0.40005 0 180)
			(size 0 0)
			(layers "F.Cu" "F.Mask" "F.Paste")
			(net "USB_HUB_PSELF")
		)
	)
	(footprint ""
		(layer "F.Cu")
		(at 433.180236 -17.612614 90)
		(property "Reference" "C868"
			(at 0 0 90)
			(layer "F.SilkS")
			(hide yes)
			(effects
				(font
					(size 1.27 1.27)
				)
			)
		)
		(property "Value" ""
			(at 0 0 90)
			(layer "F.Fab")
			(effects
				(font
					(size 1.27 1.27)
				)
			)
		)
		(duplicate_pad_numbers_are_jumpers no)
		(fp_line
			(start 0.299974 -0.150114)
			(end 0.299974 0.150114)
			(stroke
				(width 0.1)
				(type default)
			)
			(layer "F.Fab")
		)
		(fp_line
			(start -0.299974 -0.150114)
			(end 0.299974 -0.150114)
			(stroke
				(width 0.1)
				(type default)
			)
			(layer "F.Fab")
		)
		(fp_line
			(start 0.299974 0.150114)
			(end -0.299974 0.150114)
			(stroke
				(width 0.1)
				(type default)
			)
			(layer "F.Fab")
		)
		(fp_line
			(start -0.299974 0.150114)
			(end -0.299974 -0.150114)
			(stroke
				(width 0.1)
				(type default)
			)
			(layer "F.Fab")
		)
		(pad "1" smd rect
			(at -0.2667 0 90)
			(size 0.3048 0.381)
			(layers "F.Cu" "F.Mask" "F.Paste")
			(net "P5E_CPU0_PE1_TX_C_DN<0>")
		)
		(pad "2" smd rect
			(at 0.2667 0 90)
			(size 0.3048 0.381)
			(layers "F.Cu" "F.Mask" "F.Paste")
			(net "P5E_CPU0_PE1_TX_DN<0>")
		)
	)
	(footprint ""
		(layer "F.Cu")
		(at 212.442806 -134.065518)
		(property "Reference" "U117"
			(at 1.884934 -1.66624 0)
			(unlocked yes)
			(layer "F.SilkS")
			(effects
				(font
					(size 0.7874 0.5842)
					(thickness 0.1524)
				)
			)
		)
		(property "Value" ""
			(at 0 0 0)
			(layer "F.Fab")
			(effects
				(font
					(size 1.27 1.27)
				)
			)
		)
		(duplicate_pad_numbers_are_jumpers no)
		(fp_line
			(start -0.779018 -0.800862)
			(end -0.779018 0.800862)
			(stroke
				(width 0.1524)
				(type default)
			)
			(layer "F.SilkS")
		)
		(fp_line
			(start -0.779018 0.800862)
			(end 0.779018 0.800862)
			(stroke
				(width 0.1524)
				(type default)
			)
			(layer "F.SilkS")
		)
		(fp_line
			(start 0.779018 -0.800862)
			(end -0.779018 -0.800862)
			(stroke
				(width 0.1524)
				(type default)
			)
			(layer "F.SilkS")
		)
		(fp_line
			(start 0.779018 0.800862)
			(end 0.779018 -0.800862)
			(stroke
				(width 0.1524)
				(type default)
			)
			(layer "F.SilkS")
		)
		(fp_poly
			(pts
				(xy -0.462534 -1.245108) (xy -0.677164 -1.634998) (xy -0.248158 -1.634998)
			)
			(stroke
				(width 0)
				(type default)
			)
			(fill yes)
			(layer "F.SilkS")
		)
		(fp_line
			(start -0.525018 -0.750062)
			(end 0.525018 -0.750062)
			(stroke
				(width 0.1)
				(type default)
			)
			(layer "F.Fab")
		)
		(fp_line
			(start -0.525018 0.750062)
			(end -0.525018 -0.750062)
			(stroke
				(width 0.1)
				(type default)
			)
			(layer "F.Fab")
		)
		(fp_line
			(start 0.525018 -0.750062)
			(end 0.525018 0.750062)
			(stroke
				(width 0.1)
				(type default)
			)
			(layer "F.Fab")
		)
		(fp_line
			(start 0.525018 0.750062)
			(end -0.525018 0.750062)
			(stroke
				(width 0.1)
				(type default)
			)
			(layer "F.Fab")
		)
		(fp_poly
			(pts
				(xy -0.923544 -0.500126) (xy -1.313434 -0.714502) (xy -1.313434 -0.285496)
			)
			(stroke
				(width 0)
				(type default)
			)
			(fill yes)
			(layer "F.Fab")
		)
		(pad "1" smd rect
			(at -0.377444 -0.500126 270)
			(size 0.3048 0.5334)
			(layers "F.Cu" "F.Mask" "F.Paste")
			(net "FM_COMP_P3V3_AUX_ENIN")
		)
		(pad "2" smd rect
			(at -0.372618 0 270)
			(size 0.2794 0.508)
			(layers "F.Cu" "F.Mask" "F.Paste")
			(net "GND")
		)
		(pad "3" smd rect
			(at -0.372618 0.499872 270)
			(size 0.2794 0.508)
			(layers "F.Cu" "F.Mask" "F.Paste")
			(net "FM_COMP_P3V3_AUX_VIN")
		)
		(pad "4" smd rect
			(at 0.377444 0.499872 270)
			(size 0.2794 0.508)
			(layers "F.Cu" "F.Mask" "F.Paste")
			(net "PWRGD_DSW_PWROK_R1")
		)
		(pad "5" smd rect
			(at 0.377444 0 270)
			(size 0.2794 0.508)
			(layers "F.Cu" "F.Mask" "F.Paste")
			(net "FM_COMP_P3V3_STBY_CEXT")
		)
		(pad "6" smd rect
			(at 0.377444 -0.500126 270)
			(size 0.2794 0.508)
			(layers "F.Cu" "F.Mask" "F.Paste")
			(net "P3V3_AUX")
		)
	)
	(footprint ""
		(layer "F.Cu")
		(at 421.927528 -157.990286 -90)
		(property "Reference" "PC635"
			(at 0 0 270)
			(layer "F.SilkS")
			(hide yes)
			(effects
				(font
					(size 1.27 1.27)
				)
			)
		)
		(property "Value" ""
			(at 0 0 270)
			(layer "F.Fab")
			(effects
				(font
					(size 1.27 1.27)
				)
			)
		)
		(duplicate_pad_numbers_are_jumpers no)
		(fp_line
			(start -0.7874 0.4064)
			(end -0.7874 -0.4064)
			(stroke
				(width 0.1524)
				(type default)
			)
			(layer "F.SilkS")
		)
		(fp_line
			(start 0.7874 0.4064)
			(end -0.7874 0.4064)
			(stroke
				(width 0.1524)
				(type default)
			)
			(layer "F.SilkS")
		)
		(fp_line
			(start -0.7874 -0.4064)
			(end 0.7874 -0.4064)
			(stroke
				(width 0.1524)
				(type default)
			)
			(layer "F.SilkS")
		)
		(fp_line
			(start 0.7874 -0.4064)
			(end 0.7874 0.4064)
			(stroke
				(width 0.1524)
				(type default)
			)
			(layer "F.SilkS")
		)
		(fp_line
			(start -0.67945 0.3048)
			(end -0.67945 -0.305054)
			(stroke
				(width 0.1)
				(type default)
			)
			(layer "F.Fab")
		)
		(fp_line
			(start -0.12065 0.3048)
			(end -0.67945 0.3048)
			(stroke
				(width 0.1)
				(type default)
			)
			(layer "F.Fab")
		)
		(fp_line
			(start 0.120396 0.3048)
			(end 0.120396 0.2794)
			(stroke
				(width 0.1)
				(type default)
			)
			(layer "F.Fab")
		)
		(fp_line
			(start 0.67945 0.3048)
			(end 0.120396 0.3048)
			(stroke
				(width 0.1)
				(type default)
			)
			(layer "F.Fab")
		)
		(fp_line
			(start -0.12065 0.2794)
			(end -0.12065 0.3048)
			(stroke
				(width 0.1)
				(type default)
			)
			(layer "F.Fab")
		)
		(fp_line
			(start 0.120396 0.2794)
			(end -0.12065 0.2794)
			(stroke
				(width 0.1)
				(type default)
			)
			(layer "F.Fab")
		)
		(fp_line
			(start -0.12065 -0.2794)
			(end 0.12065 -0.2794)
			(stroke
				(width 0.1)
				(type default)
			)
			(layer "F.Fab")
		)
		(fp_line
			(start 0.12065 -0.2794)
			(end 0.12065 -0.3048)
			(stroke
				(width 0.1)
				(type default)
			)
			(layer "F.Fab")
		)
		(fp_line
			(start 0.12065 -0.3048)
			(end 0.67945 -0.3048)
			(stroke
				(width 0.1)
				(type default)
			)
			(layer "F.Fab")
		)
		(fp_line
			(start 0.67945 -0.3048)
			(end 0.67945 0.3048)
			(stroke
				(width 0.1)
				(type default)
			)
			(layer "F.Fab")
		)
		(fp_line
			(start -0.67945 -0.305054)
			(end -0.12065 -0.305054)
			(stroke
				(width 0.1)
				(type default)
			)
			(layer "F.Fab")
		)
		(fp_line
			(start -0.12065 -0.305054)
			(end -0.12065 -0.2794)
			(stroke
				(width 0.1)
				(type default)
			)
			(layer "F.Fab")
		)
		(pad "1" smd circle
			(at -0.40005 0 270)
			(size 0 0)
			(layers "F.Cu" "F.Mask" "F.Paste")
			(net "SW_P12V_PVCCINFAON_CPU0_FLT")
		)
		(pad "2" smd circle
			(at 0.40005 0 270)
			(size 0 0)
			(layers "F.Cu" "F.Mask" "F.Paste")
			(net "GND")
		)
	)
)
